(kicad_pcb
	(version 20260206)
	(generator "pcbnew")
	(generator_version "10.0")
	(general
		(thickness 1.6)
		(legacy_teardrops no)
	)
	(paper "A4")
	(title_block
		(title "04192023_DAF0TMB3IC0_F0TG_MB_C_brd_V02_OCP.brd")
		(comment 1 "Grand Teton / footprints 3214-3220 of 8354")
	)
	(layers
		(0 "F.Cu" signal "TOP")
		(4 "In1.Cu" signal "GND")
		(6 "In2.Cu" signal "IN1")
		(8 "In3.Cu" signal "GND1")
		(10 "In4.Cu" signal "IN2")
		(12 "In5.Cu" signal "GND2")
		(14 "In6.Cu" signal "IN3")
		(16 "In7.Cu" signal "GND3")
		(18 "In8.Cu" signal "VCC")
		(20 "In9.Cu" signal "VCC1")
		(22 "In10.Cu" signal "GND4")
		(24 "In11.Cu" signal "IN4")
		(26 "In12.Cu" signal "GND5")
		(28 "In13.Cu" signal "IN5")
		(30 "In14.Cu" signal "GND6")
		(32 "In15.Cu" signal "IN6")
		(34 "In16.Cu" signal "GND7")
		(2 "B.Cu" signal "BOTTOM")
		(9 "F.Adhes" user "F.Adhesive")
		(11 "B.Adhes" user "B.Adhesive")
		(13 "F.Paste" user "Package Geometry/Pastemask Top")
		(15 "B.Paste" user "Package Geometry/Pastemask Bottom")
		(5 "F.SilkS" user "Ref Des/Silkscreen Top")
		(7 "B.SilkS" user "Ref Des/Silkscreen Bottom")
		(1 "F.Mask" user "Board Geometry/Soldermask Top")
		(3 "B.Mask" user "Board Geometry/Soldermask Bottom")
		(17 "Dwgs.User" user "User.Drawings")
		(19 "Cmts.User" user "User.Comments")
		(21 "Eco1.User" user "User.Eco1")
		(23 "Eco2.User" user "User.Eco2")
		(25 "Edge.Cuts" user "Board Geometry/Outline")
		(27 "Margin" user)
		(31 "F.CrtYd" user "Package Geometry/Place Bound Top")
		(29 "B.CrtYd" user "Package Geometry/Place Bound Bottom")
		(35 "F.Fab" user "Ref Des/Assembly Top")
		(33 "B.Fab" user "Ref Des/Assembly Bottom")
	)
	(footprint ""
		(layer "F.Cu")
		(at 118.287546 -72.91324 -90)
		(property "Reference" "PR6004"
			(at 0 0 270)
			(layer "F.SilkS")
			(hide yes)
			(effects
				(font
					(size 1.27 1.27)
				)
			)
		)
		(property "Value" ""
			(at 0 0 270)
			(layer "F.Fab")
			(effects
				(font
					(size 1.27 1.27)
				)
			)
		)
		(duplicate_pad_numbers_are_jumpers no)
		(fp_line
			(start -0.7874 0.4064)
			(end -0.7874 -0.4064)
			(stroke
				(width 0.1524)
				(type default)
			)
			(layer "F.SilkS")
		)
		(fp_line
			(start 0.7874 0.4064)
			(end -0.7874 0.4064)
			(stroke
				(width 0.1524)
				(type default)
			)
			(layer "F.SilkS")
		)
		(fp_line
			(start -0.7874 -0.4064)
			(end 0.7874 -0.4064)
			(stroke
				(width 0.1524)
				(type default)
			)
			(layer "F.SilkS")
		)
		(fp_line
			(start 0.7874 -0.4064)
			(end 0.7874 0.4064)
			(stroke
				(width 0.1524)
				(type default)
			)
			(layer "F.SilkS")
		)
		(fp_line
			(start -0.67945 0.3048)
			(end -0.67945 -0.305054)
			(stroke
				(width 0.1)
				(type default)
			)
			(layer "F.Fab")
		)
		(fp_line
			(start -0.12065 0.3048)
			(end -0.67945 0.3048)
			(stroke
				(width 0.1)
				(type default)
			)
			(layer "F.Fab")
		)
		(fp_line
			(start 0.120396 0.3048)
			(end 0.120396 0.2794)
			(stroke
				(width 0.1)
				(type default)
			)
			(layer "F.Fab")
		)
		(fp_line
			(start 0.67945 0.3048)
			(end 0.120396 0.3048)
			(stroke
				(width 0.1)
				(type default)
			)
			(layer "F.Fab")
		)
		(fp_line
			(start -0.12065 0.2794)
			(end -0.12065 0.3048)
			(stroke
				(width 0.1)
				(type default)
			)
			(layer "F.Fab")
		)
		(fp_line
			(start 0.120396 0.2794)
			(end -0.12065 0.2794)
			(stroke
				(width 0.1)
				(type default)
			)
			(layer "F.Fab")
		)
		(fp_line
			(start -0.12065 -0.2794)
			(end 0.12065 -0.2794)
			(stroke
				(width 0.1)
				(type default)
			)
			(layer "F.Fab")
		)
		(fp_line
			(start 0.12065 -0.2794)
			(end 0.12065 -0.3048)
			(stroke
				(width 0.1)
				(type default)
			)
			(layer "F.Fab")
		)
		(fp_line
			(start 0.12065 -0.3048)
			(end 0.67945 -0.3048)
			(stroke
				(width 0.1)
				(type default)
			)
			(layer "F.Fab")
		)
		(fp_line
			(start 0.67945 -0.3048)
			(end 0.67945 0.3048)
			(stroke
				(width 0.1)
				(type default)
			)
			(layer "F.Fab")
		)
		(fp_line
			(start -0.67945 -0.305054)
			(end -0.12065 -0.305054)
			(stroke
				(width 0.1)
				(type default)
			)
			(layer "F.Fab")
		)
		(fp_line
			(start -0.12065 -0.305054)
			(end -0.12065 -0.2794)
			(stroke
				(width 0.1)
				(type default)
			)
			(layer "F.Fab")
		)
		(pad "1" smd circle
			(at -0.40005 0 270)
			(size 0 0)
			(layers "F.Cu" "F.Mask" "F.Paste")
			(net "P1V2_AUX_CS")
		)
		(pad "2" smd circle
			(at 0.40005 0 270)
			(size 0 0)
			(layers "F.Cu" "F.Mask" "F.Paste")
			(net "GND")
		)
	)
	(footprint ""
		(layer "F.Cu")
		(at 65.3796 -15.8496 180)
		(property "Reference" "C1831"
			(at 0 0 180)
			(layer "F.SilkS")
			(hide yes)
			(effects
				(font
					(size 1.27 1.27)
				)
			)
		)
		(property "Value" ""
			(at 0 0 180)
			(layer "F.Fab")
			(effects
				(font
					(size 1.27 1.27)
				)
			)
		)
		(duplicate_pad_numbers_are_jumpers no)
		(fp_line
			(start 0.7874 0.4064)
			(end -0.7874 0.4064)
			(stroke
				(width 0.1524)
				(type default)
			)
			(layer "F.SilkS")
		)
		(fp_line
			(start 0.7874 -0.4064)
			(end 0.7874 0.4064)
			(stroke
				(width 0.1524)
				(type default)
			)
			(layer "F.SilkS")
		)
		(fp_line
			(start -0.7874 0.4064)
			(end -0.7874 -0.4064)
			(stroke
				(width 0.1524)
				(type default)
			)
			(layer "F.SilkS")
		)
		(fp_line
			(start -0.7874 -0.4064)
			(end 0.7874 -0.4064)
			(stroke
				(width 0.1524)
				(type default)
			)
			(layer "F.SilkS")
		)
		(fp_line
			(start 0.67945 0.3048)
			(end 0.120396 0.3048)
			(stroke
				(width 0.1)
				(type default)
			)
			(layer "F.Fab")
		)
		(fp_line
			(start 0.67945 -0.3048)
			(end 0.67945 0.3048)
			(stroke
				(width 0.1)
				(type default)
			)
			(layer "F.Fab")
		)
		(fp_line
			(start 0.12065 -0.2794)
			(end 0.12065 -0.3048)
			(stroke
				(width 0.1)
				(type default)
			)
			(layer "F.Fab")
		)
		(fp_line
			(start 0.12065 -0.3048)
			(end 0.67945 -0.3048)
			(stroke
				(width 0.1)
				(type default)
			)
			(layer "F.Fab")
		)
		(fp_line
			(start 0.120396 0.3048)
			(end 0.120396 0.2794)
			(stroke
				(width 0.1)
				(type default)
			)
			(layer "F.Fab")
		)
		(fp_line
			(start 0.120396 0.2794)
			(end -0.12065 0.2794)
			(stroke
				(width 0.1)
				(type default)
			)
			(layer "F.Fab")
		)
		(fp_line
			(start -0.12065 0.3048)
			(end -0.67945 0.3048)
			(stroke
				(width 0.1)
				(type default)
			)
			(layer "F.Fab")
		)
		(fp_line
			(start -0.12065 0.2794)
			(end -0.12065 0.3048)
			(stroke
				(width 0.1)
				(type default)
			)
			(layer "F.Fab")
		)
		(fp_line
			(start -0.12065 -0.2794)
			(end 0.12065 -0.2794)
			(stroke
				(width 0.1)
				(type default)
			)
			(layer "F.Fab")
		)
		(fp_line
			(start -0.12065 -0.305054)
			(end -0.12065 -0.2794)
			(stroke
				(width 0.1)
				(type default)
			)
			(layer "F.Fab")
		)
		(fp_line
			(start -0.67945 0.3048)
			(end -0.67945 -0.305054)
			(stroke
				(width 0.1)
				(type default)
			)
			(layer "F.Fab")
		)
		(fp_line
			(start -0.67945 -0.305054)
			(end -0.12065 -0.305054)
			(stroke
				(width 0.1)
				(type default)
			)
			(layer "F.Fab")
		)
		(pad "1" smd circle
			(at -0.40005 0 180)
			(size 0 0)
			(layers "F.Cu" "F.Mask" "F.Paste")
			(net "P12V_OCP_V3_2_R")
		)
		(pad "2" smd circle
			(at 0.40005 0 180)
			(size 0 0)
			(layers "F.Cu" "F.Mask" "F.Paste")
			(net "GND")
		)
	)
	(footprint ""
		(layer "F.Cu")
		(at 27.178 -357.886 90)
		(property "Reference" "PR245"
			(at 0 0 90)
			(layer "F.SilkS")
			(hide yes)
			(effects
				(font
					(size 1.27 1.27)
				)
			)
		)
		(property "Value" ""
			(at 0 0 90)
			(layer "F.Fab")
			(effects
				(font
					(size 1.27 1.27)
				)
			)
		)
		(duplicate_pad_numbers_are_jumpers no)
		(fp_line
			(start 0.7874 -0.4064)
			(end 0.7874 0.4064)
			(stroke
				(width 0.1524)
				(type default)
			)
			(layer "F.SilkS")
		)
		(fp_line
			(start -0.7874 -0.4064)
			(end 0.7874 -0.4064)
			(stroke
				(width 0.1524)
				(type default)
			)
			(layer "F.SilkS")
		)
		(fp_line
			(start 0.7874 0.4064)
			(end -0.7874 0.4064)
			(stroke
				(width 0.1524)
				(type default)
			)
			(layer "F.SilkS")
		)
		(fp_line
			(start -0.7874 0.4064)
			(end -0.7874 -0.4064)
			(stroke
				(width 0.1524)
				(type default)
			)
			(layer "F.SilkS")
		)
		(fp_line
			(start -0.12065 -0.305054)
			(end -0.12065 -0.2794)
			(stroke
				(width 0.1)
				(type default)
			)
			(layer "F.Fab")
		)
		(fp_line
			(start -0.67945 -0.305054)
			(end -0.12065 -0.305054)
			(stroke
				(width 0.1)
				(type default)
			)
			(layer "F.Fab")
		)
		(fp_line
			(start 0.67945 -0.3048)
			(end 0.67945 0.3048)
			(stroke
				(width 0.1)
				(type default)
			)
			(layer "F.Fab")
		)
		(fp_line
			(start 0.12065 -0.3048)
			(end 0.67945 -0.3048)
			(stroke
				(width 0.1)
				(type default)
			)
			(layer "F.Fab")
		)
		(fp_line
			(start 0.12065 -0.2794)
			(end 0.12065 -0.3048)
			(stroke
				(width 0.1)
				(type default)
			)
			(layer "F.Fab")
		)
		(fp_line
			(start -0.12065 -0.2794)
			(end 0.12065 -0.2794)
			(stroke
				(width 0.1)
				(type default)
			)
			(layer "F.Fab")
		)
		(fp_line
			(start 0.120396 0.2794)
			(end -0.12065 0.2794)
			(stroke
				(width 0.1)
				(type default)
			)
			(layer "F.Fab")
		)
		(fp_line
			(start -0.12065 0.2794)
			(end -0.12065 0.3048)
			(stroke
				(width 0.1)
				(type default)
			)
			(layer "F.Fab")
		)
		(fp_line
			(start 0.67945 0.3048)
			(end 0.120396 0.3048)
			(stroke
				(width 0.1)
				(type default)
			)
			(layer "F.Fab")
		)
		(fp_line
			(start 0.120396 0.3048)
			(end 0.120396 0.2794)
			(stroke
				(width 0.1)
				(type default)
			)
			(layer "F.Fab")
		)
		(fp_line
			(start -0.12065 0.3048)
			(end -0.67945 0.3048)
			(stroke
				(width 0.1)
				(type default)
			)
			(layer "F.Fab")
		)
		(fp_line
			(start -0.67945 0.3048)
			(end -0.67945 -0.305054)
			(stroke
				(width 0.1)
				(type default)
			)
			(layer "F.Fab")
		)
		(pad "1" smd circle
			(at -0.40005 0 90)
			(size 0 0)
			(layers "F.Cu" "F.Mask" "F.Paste")
			(net "VSENSE_PVDDCR_CPU1_P1_DP")
		)
		(pad "2" smd circle
			(at 0.40005 0 90)
			(size 0 0)
			(layers "F.Cu" "F.Mask" "F.Paste")
			(net "VSENSE_PVDDCR_CPU1_P1_VSEN0")
		)
	)
	(footprint ""
		(layer "F.Cu")
		(at 269.023084 -333.045562)
		(property "Reference" "PR50"
			(at 0 0 0)
			(layer "F.SilkS")
			(hide yes)
			(effects
				(font
					(size 1.27 1.27)
				)
			)
		)
		(property "Value" ""
			(at 0 0 0)
			(layer "F.Fab")
			(effects
				(font
					(size 1.27 1.27)
				)
			)
		)
		(duplicate_pad_numbers_are_jumpers no)
		(fp_line
			(start -0.7874 -0.4064)
			(end 0.7874 -0.4064)
			(stroke
				(width 0.1524)
				(type default)
			)
			(layer "F.SilkS")
		)
		(fp_line
			(start -0.7874 0.4064)
			(end -0.7874 -0.4064)
			(stroke
				(width 0.1524)
				(type default)
			)
			(layer "F.SilkS")
		)
		(fp_line
			(start 0.7874 -0.4064)
			(end 0.7874 0.4064)
			(stroke
				(width 0.1524)
				(type default)
			)
			(layer "F.SilkS")
		)
		(fp_line
			(start 0.7874 0.4064)
			(end -0.7874 0.4064)
			(stroke
				(width 0.1524)
				(type default)
			)
			(layer "F.SilkS")
		)
		(fp_line
			(start -0.67945 -0.305054)
			(end -0.12065 -0.305054)
			(stroke
				(width 0.1)
				(type default)
			)
			(layer "F.Fab")
		)
		(fp_line
			(start -0.67945 0.3048)
			(end -0.67945 -0.305054)
			(stroke
				(width 0.1)
				(type default)
			)
			(layer "F.Fab")
		)
		(fp_line
			(start -0.12065 -0.305054)
			(end -0.12065 -0.2794)
			(stroke
				(width 0.1)
				(type default)
			)
			(layer "F.Fab")
		)
		(fp_line
			(start -0.12065 -0.2794)
			(end 0.12065 -0.2794)
			(stroke
				(width 0.1)
				(type default)
			)
			(layer "F.Fab")
		)
		(fp_line
			(start -0.12065 0.2794)
			(end -0.12065 0.3048)
			(stroke
				(width 0.1)
				(type default)
			)
			(layer "F.Fab")
		)
		(fp_line
			(start -0.12065 0.3048)
			(end -0.67945 0.3048)
			(stroke
				(width 0.1)
				(type default)
			)
			(layer "F.Fab")
		)
		(fp_line
			(start 0.120396 0.2794)
			(end -0.12065 0.2794)
			(stroke
				(width 0.1)
				(type default)
			)
			(layer "F.Fab")
		)
		(fp_line
			(start 0.120396 0.3048)
			(end 0.120396 0.2794)
			(stroke
				(width 0.1)
				(type default)
			)
			(layer "F.Fab")
		)
		(fp_line
			(start 0.12065 -0.3048)
			(end 0.67945 -0.3048)
			(stroke
				(width 0.1)
				(type default)
			)
			(layer "F.Fab")
		)
		(fp_line
			(start 0.12065 -0.2794)
			(end 0.12065 -0.3048)
			(stroke
				(width 0.1)
				(type default)
			)
			(layer "F.Fab")
		)
		(fp_line
			(start 0.67945 -0.3048)
			(end 0.67945 0.3048)
			(stroke
				(width 0.1)
				(type default)
			)
			(layer "F.Fab")
		)
		(fp_line
			(start 0.67945 0.3048)
			(end 0.120396 0.3048)
			(stroke
				(width 0.1)
				(type default)
			)
			(layer "F.Fab")
		)
		(pad "1" smd circle
			(at -0.40005 0)
			(size 0 0)
			(layers "F.Cu" "F.Mask" "F.Paste")
			(net "VSENSE_VSS_SENSE_B_P0")
		)
		(pad "2" smd circle
			(at 0.40005 0)
			(size 0 0)
			(layers "F.Cu" "F.Mask" "F.Paste")
			(net "GND")
		)
	)
	(footprint ""
		(layer "F.Cu")
		(at 141.623542 -385.48056)
		(property "Reference" "R874"
			(at 0 0 0)
			(layer "F.SilkS")
			(hide yes)
			(effects
				(font
					(size 1.27 1.27)
				)
			)
		)
		(property "Value" ""
			(at 0 0 0)
			(layer "F.Fab")
			(effects
				(font
					(size 1.27 1.27)
				)
			)
		)
		(duplicate_pad_numbers_are_jumpers no)
		(fp_line
			(start -0.32512 -0.175006)
			(end 0.32512 -0.175006)
			(stroke
				(width 0.1)
				(type default)
			)
			(layer "F.Fab")
		)
		(fp_line
			(start -0.32512 0.175006)
			(end -0.32512 -0.175006)
			(stroke
				(width 0.1)
				(type default)
			)
			(layer "F.Fab")
		)
		(fp_line
			(start 0.32512 -0.175006)
			(end 0.32512 0.175006)
			(stroke
				(width 0.1)
				(type default)
			)
			(layer "F.Fab")
		)
		(fp_line
			(start 0.32512 0.175006)
			(end -0.32512 0.175006)
			(stroke
				(width 0.1)
				(type default)
			)
			(layer "F.Fab")
		)
		(pad "1" smd rect
			(at -0.2667 0)
			(size 0.3048 0.381)
			(layers "F.Cu" "F.Mask" "F.Paste")
			(net "P1V8_CPU1_RT_1D")
		)
		(pad "2" smd rect
			(at 0.2667 0 180)
			(size 0.3048 0.381)
			(layers "F.Cu" "F.Mask" "F.Paste")
			(net "GPIO2_RT_CPU1_P2")
		)
	)
	(footprint ""
		(layer "F.Cu")
		(at 348.93123 -20.136612 -90)
		(property "Reference" "Q12"
			(at -3.219196 -2.33553 90)
			(unlocked yes)
			(layer "F.SilkS")
			(effects
				(font
					(size 0.7874 0.5842)
					(thickness 0.1524)
				)
			)
		)
		(property "Value" ""
			(at 0 0 270)
			(layer "F.Fab")
			(effects
				(font
					(size 1.27 1.27)
				)
			)
		)
		(duplicate_pad_numbers_are_jumpers no)
		(fp_line
			(start -1.8796 1.651)
			(end -1.8796 -1.651)
			(stroke
				(width 0.1524)
				(type default)
			)
			(layer "F.SilkS")
		)
		(fp_line
			(start 1.8796 1.651)
			(end -1.8796 1.651)
			(stroke
				(width 0.1524)
				(type default)
			)
			(layer "F.SilkS")
		)
		(fp_line
			(start -1.8796 -1.651)
			(end 1.8796 -1.651)
			(stroke
				(width 0.1524)
				(type default)
			)
			(layer "F.SilkS")
		)
		(fp_line
			(start 1.8796 -1.651)
			(end 1.8796 1.651)
			(stroke
				(width 0.1524)
				(type default)
			)
			(layer "F.SilkS")
		)
		(fp_line
			(start -0.700024 1.500124)
			(end -0.700024 -1.500124)
			(stroke
				(width 0.1)
				(type default)
			)
			(layer "F.Fab")
		)
		(fp_line
			(start 0.700024 1.500124)
			(end -0.700024 1.500124)
			(stroke
				(width 0.1)
				(type default)
			)
			(layer "F.Fab")
		)
		(fp_line
			(start -0.700024 -1.500124)
			(end 0.700024 -1.500124)
			(stroke
				(width 0.1)
				(type default)
			)
			(layer "F.Fab")
		)
		(fp_line
			(start 0.700024 -1.500124)
			(end 0.700024 1.500124)
			(stroke
				(width 0.1)
				(type default)
			)
			(layer "F.Fab")
		)
		(pad "D" smd rect
			(at 1.119886 0 180)
			(size 1.016 1.2192)
			(layers "F.Cu" "F.Mask" "F.Paste")
			(net "P12V_ALL_PWROK_N")
		)
		(pad "G" smd rect
			(at -1.119886 -0.999998 180)
			(size 1.016 1.2192)
			(layers "F.Cu" "F.Mask" "F.Paste")
			(net "P12V_ALL_PWROK")
		)
		(pad "S" smd rect
			(at -1.119886 0.999998 180)
			(size 1.016 1.2192)
			(layers "F.Cu" "F.Mask" "F.Paste")
			(net "GND")
		)
	)
	(footprint ""
		(layer "F.Cu")
		(at 438.277 -96.357948 90)
		(property "Reference" "C2015"
			(at 0 0 90)
			(layer "F.SilkS")
			(hide yes)
			(effects
				(font
					(size 1.27 1.27)
				)
			)
		)
		(property "Value" ""
			(at 0 0 90)
			(layer "F.Fab")
			(effects
				(font
					(size 1.27 1.27)
				)
			)
		)
		(duplicate_pad_numbers_are_jumpers no)
		(fp_line
			(start 0.7874 -0.4064)
			(end 0.7874 0.4064)
			(stroke
				(width 0.1524)
				(type default)
			)
			(layer "F.SilkS")
		)
		(fp_line
			(start -0.7874 -0.4064)
			(end 0.7874 -0.4064)
			(stroke
				(width 0.1524)
				(type default)
			)
			(layer "F.SilkS")
		)
		(fp_line
			(start 0.7874 0.4064)
			(end -0.7874 0.4064)
			(stroke
				(width 0.1524)
				(type default)
			)
			(layer "F.SilkS")
		)
		(fp_line
			(start -0.7874 0.4064)
			(end -0.7874 -0.4064)
			(stroke
				(width 0.1524)
				(type default)
			)
			(layer "F.SilkS")
		)
		(fp_line
			(start -0.12065 -0.305054)
			(end -0.12065 -0.2794)
			(stroke
				(width 0.1)
				(type default)
			)
			(layer "F.Fab")
		)
		(fp_line
			(start -0.67945 -0.305054)
			(end -0.12065 -0.305054)
			(stroke
				(width 0.1)
				(type default)
			)
			(layer "F.Fab")
		)
		(fp_line
			(start 0.67945 -0.3048)
			(end 0.67945 0.3048)
			(stroke
				(width 0.1)
				(type default)
			)
			(layer "F.Fab")
		)
		(fp_line
			(start 0.12065 -0.3048)
			(end 0.67945 -0.3048)
			(stroke
				(width 0.1)
				(type default)
			)
			(layer "F.Fab")
		)
		(fp_line
			(start 0.12065 -0.2794)
			(end 0.12065 -0.3048)
			(stroke
				(width 0.1)
				(type default)
			)
			(layer "F.Fab")
		)
		(fp_line
			(start -0.12065 -0.2794)
			(end 0.12065 -0.2794)
			(stroke
				(width 0.1)
				(type default)
			)
			(layer "F.Fab")
		)
		(fp_line
			(start 0.120396 0.2794)
			(end -0.12065 0.2794)
			(stroke
				(width 0.1)
				(type default)
			)
			(layer "F.Fab")
		)
		(fp_line
			(start -0.12065 0.2794)
			(end -0.12065 0.3048)
			(stroke
				(width 0.1)
				(type default)
			)
			(layer "F.Fab")
		)
		(fp_line
			(start 0.67945 0.3048)
			(end 0.120396 0.3048)
			(stroke
				(width 0.1)
				(type default)
			)
			(layer "F.Fab")
		)
		(fp_line
			(start 0.120396 0.3048)
			(end 0.120396 0.2794)
			(stroke
				(width 0.1)
				(type default)
			)
			(layer "F.Fab")
		)
		(fp_line
			(start -0.12065 0.3048)
			(end -0.67945 0.3048)
			(stroke
				(width 0.1)
				(type default)
			)
			(layer "F.Fab")
		)
		(fp_line
			(start -0.67945 0.3048)
			(end -0.67945 -0.305054)
			(stroke
				(width 0.1)
				(type default)
			)
			(layer "F.Fab")
		)
		(pad "1" smd circle
			(at -0.40005 0 90)
			(size 0 0)
			(layers "F.Cu" "F.Mask" "F.Paste")
			(net "P3V3_AUX")
		)
		(pad "2" smd circle
			(at 0.40005 0 90)
			(size 0 0)
			(layers "F.Cu" "F.Mask" "F.Paste")
			(net "GND")
		)
	)
)
